(kicad_pcb
	(version 20240108)
	(generator "pcbnew")
	(generator_version "8.0")
	(general
		(thickness 1.62)
		(legacy_teardrops no)
	)
	(paper "A4")
	(title_block
		(title "Jetson Orin Baseboard")
		(date "2025-03-12")
		(rev "1.3.4")
		(company "Antmicro Ltd")
		(comment 1 "www.antmicro.com")
		(comment 9 "footprints 196-200 of 677")
	)
	(layers
		(0 "F.Cu" signal)
		(1 "In1.Cu" signal)
		(2 "In2.Cu" signal)
		(3 "In3.Cu" signal)
		(4 "In4.Cu" jumper)
		(5 "In5.Cu" signal)
		(6 "In6.Cu" signal)
		(31 "B.Cu" signal)
		(32 "B.Adhes" user "B.Adhesive")
		(33 "F.Adhes" user "F.Adhesive")
		(34 "B.Paste" user)
		(35 "F.Paste" user)
		(36 "B.SilkS" user "B.Silkscreen")
		(37 "F.SilkS" user "F.Silkscreen")
		(38 "B.Mask" user)
		(39 "F.Mask" user)
		(40 "Dwgs.User" user "User.Drawings")
		(41 "Cmts.User" user "User.Comments")
		(42 "Eco1.User" user "User.Eco1")
		(43 "Eco2.User" user "User.Eco2")
		(44 "Edge.Cuts" user)
		(45 "Margin" user)
		(46 "B.CrtYd" user "B.Courtyard")
		(47 "F.CrtYd" user "F.Courtyard")
		(48 "B.Fab" user)
		(49 "F.Fab" user)
	)
	(footprint "antmicro-footprints:USON-10_2.5x1mm_P0.5mm"
		(layer "F.Cu")
		(at 78 115.5 90)
		(descr "USON-10 2.5x1mm_ Pitch 0.5mm")
		(tags "USON-10 2.5x1mm Pitch 0.5mm")
		(property "Reference" "U14"
			(at 0.89 -0.6 180)
			(layer "F.SilkS")
			(effects
				(font
					(size 0.7 0.7)
					(thickness 0.15)
				)
				(justify left bottom)
			)
		)
		(property "Value" "TPD4E05U06QDQARQ1"
			(at 0.018 2.499 90)
			(layer "F.Fab")
			(effects
				(font
					(size 0.7 0.7)
					(thickness 0.15)
				)
				(justify left bottom)
			)
		)
		(property "Footprint" "antmicro-footprints:USON-10_2.5x1mm_P0.5mm"
			(at 0 0 90)
			(layer "F.Fab")
			(hide yes)
			(effects
				(font
					(size 1.27 1.27)
					(thickness 0.15)
				)
			)
		)
		(property "Datasheet" "https://www.ti.com/lit/ds/symlink/tpd4e05u06-q1.pdf?HQS=dis-mous-null-mousermode-dsf-pf-null-wwe&ts=1663591265741&ref_url=https%253A%252F%252Fwww.mouser.com%252F"
			(at 0 0 90)
			(layer "F.Fab")
			(hide yes)
			(effects
				(font
					(size 1.27 1.27)
					(thickness 0.15)
				)
			)
		)
		(property "Author" "Antmicro"
			(at 193.5 37.5 0)
			(layer "F.Fab")
			(hide yes)
			(effects
				(font
					(size 1 1)
					(thickness 0.15)
				)
			)
		)
		(property "License" "Apache-2.0"
			(at 193.5 37.5 0)
			(layer "F.Fab")
			(hide yes)
			(effects
				(font
					(size 1 1)
					(thickness 0.15)
				)
			)
		)
		(property "MPN" "TPD4E05U06QDQARQ1"
			(at 193.5 37.5 0)
			(layer "F.Fab")
			(hide yes)
			(effects
				(font
					(size 1 1)
					(thickness 0.15)
				)
			)
		)
		(property "Manufacturer" "Texas Instruments"
			(at 193.5 37.5 0)
			(layer "F.Fab")
			(hide yes)
			(effects
				(font
					(size 1 1)
					(thickness 0.15)
				)
			)
		)
		(sheetname "USB Debug, DP")
		(sheetfile "usb.kicad_sch")
		(attr smd)
		(fp_line
			(start 0.498 -1.401)
			(end -0.5 -1.401)
			(stroke
				(width 0.15)
				(type solid)
			)
			(layer "F.SilkS")
		)
		(fp_line
			(start 0.498 1.398)
			(end -0.5 1.398)
			(stroke
				(width 0.15)
				(type solid)
			)
			(layer "F.SilkS")
		)
		(fp_circle
			(center -0.68 -1.27)
			(end -0.63 -1.27)
			(stroke
				(width 0.15)
				(type solid)
			)
			(fill solid)
			(layer "F.SilkS")
		)
		(fp_rect
			(start -0.8 -1.5)
			(end 0.8 1.499)
			(stroke
				(width 0.05)
				(type solid)
			)
			(fill none)
			(layer "F.CrtYd")
		)
		(fp_line
			(start 0.498 -1.25)
			(end -0.25 -1.25)
			(stroke
				(width 0.15)
				(type solid)
			)
			(layer "F.Fab")
		)
		(fp_line
			(start 0.498 -1.25)
			(end 0.498 1.249)
			(stroke
				(width 0.15)
				(type solid)
			)
			(layer "F.Fab")
		)
		(fp_line
			(start -0.25 -1.25)
			(end -0.5 -1)
			(stroke
				(width 0.15)
				(type solid)
			)
			(layer "F.Fab")
		)
		(fp_line
			(start -0.5 -1)
			(end -0.5 1.249)
			(stroke
				(width 0.15)
				(type solid)
			)
			(layer "F.Fab")
		)
		(fp_line
			(start -0.5 1.249)
			(end 0.498 1.249)
			(stroke
				(width 0.15)
				(type solid)
			)
			(layer "F.Fab")
		)
		(fp_text user "License: Apache-2.0"
			(at -0.802 6.9 90)
			(layer "F.Fab")
			(hide yes)
			(effects
				(font
					(size 0.7 0.7)
					(thickness 0.15)
				)
				(justify left bottom)
			)
		)
		(fp_text user "Author: Antmicro"
			(at -0.802 5.7 90)
			(layer "F.Fab")
			(hide yes)
			(effects
				(font
					(size 0.7 0.7)
					(thickness 0.15)
				)
				(justify left bottom)
			)
		)
		(fp_text user "${REFERENCE}"
			(at -0.802 4.498 90)
			(layer "F.Fab")
			(hide yes)
			(effects
				(font
					(size 0.7 0.7)
					(thickness 0.15)
				)
				(justify left bottom)
			)
		)
		(pad "1" smd roundrect
			(at -0.387 -1)
			(size 0.25 0.55)
			(layers "F.Cu" "F.Paste" "F.Mask")
			(roundrect_rratio 0.25)
			(net 125 "/USB Debug, DP/USBC0_RX2_N")
			(pintype "passive")
		)
		(pad "2" smd roundrect
			(at -0.387 -0.5)
			(size 0.25 0.55)
			(layers "F.Cu" "F.Paste" "F.Mask")
			(roundrect_rratio 0.25)
			(net 151 "/USB Debug, DP/USBC0_RX2_P")
			(pintype "passive")
		)
		(pad "3" smd roundrect
			(at -0.387 0)
			(size 0.4 0.55)
			(layers "F.Cu" "F.Paste" "F.Mask")
			(roundrect_rratio 0.25)
			(net 1 "GND")
			(pintype "power_in")
		)
		(pad "4" smd roundrect
			(at -0.387 0.498)
			(size 0.25 0.55)
			(layers "F.Cu" "F.Paste" "F.Mask")
			(roundrect_rratio 0.25)
			(net 201 "/USB Debug, DP/USBC0_CONN_TX2_N")
			(pintype "passive")
		)
		(pad "5" smd roundrect
			(at -0.387 0.998)
			(size 0.25 0.55)
			(layers "F.Cu" "F.Paste" "F.Mask")
			(roundrect_rratio 0.25)
			(net 260 "/USB Debug, DP/USBC0_CONN_TX2_P")
			(pintype "passive")
		)
		(pad "6" smd roundrect
			(at 0.385 0.998)
			(size 0.25 0.55)
			(layers "F.Cu" "F.Paste" "F.Mask")
			(roundrect_rratio 0.25)
			(net 260 "/USB Debug, DP/USBC0_CONN_TX2_P")
			(pintype "passive")
		)
		(pad "7" smd roundrect
			(at 0.385 0.498)
			(size 0.25 0.55)
			(layers "F.Cu" "F.Paste" "F.Mask")
			(roundrect_rratio 0.25)
			(net 201 "/USB Debug, DP/USBC0_CONN_TX2_N")
			(pintype "passive")
		)
		(pad "8" smd roundrect
			(at 0.385 0)
			(size 0.4 0.55)
			(layers "F.Cu" "F.Paste" "F.Mask")
			(roundrect_rratio 0.25)
			(net 1 "GND")
			(pintype "passive")
		)
		(pad "9" smd roundrect
			(at 0.385 -0.5)
			(size 0.25 0.55)
			(layers "F.Cu" "F.Paste" "F.Mask")
			(roundrect_rratio 0.25)
			(net 151 "/USB Debug, DP/USBC0_RX2_P")
			(pintype "passive")
		)
		(pad "10" smd roundrect
			(at 0.385 -1)
			(size 0.25 0.55)
			(layers "F.Cu" "F.Paste" "F.Mask")
			(roundrect_rratio 0.25)
			(net 125 "/USB Debug, DP/USBC0_RX2_N")
			(pintype "passive")
		)
	)
	(footprint "antmicro-footprints:XDFN-2_1x0.60mm"
		(layer "F.Cu")
		(at 147.45 90.8 -90)
		(property "Reference" "D50"
			(at -7.4 0.15 180)
			(layer "F.SilkS")
			(effects
				(font
					(size 0.7 0.7)
					(thickness 0.15)
				)
				(justify left bottom)
			)
		)
		(property "Value" "TPD1E0B04_XDFN-2"
			(at 0 1.5 -90)
			(layer "F.Fab")
			(effects
				(font
					(size 0.7 0.7)
					(thickness 0.15)
				)
				(justify left bottom)
			)
		)
		(property "Footprint" "antmicro-footprints:XDFN-2_1x0.60mm"
			(at 0 0 -90)
			(layer "F.Fab")
			(hide yes)
			(effects
				(font
					(size 1.27 1.27)
					(thickness 0.15)
				)
			)
		)
		(property "Datasheet" "https://www.ti.com/general/docs/suppproductinfo.tsp?distId=26&gotoUrl=https://www.ti.com/lit/gpn/tpd1e0b04"
			(at 0 0 -90)
			(layer "F.Fab")
			(hide yes)
			(effects
				(font
					(size 1.27 1.27)
					(thickness 0.15)
				)
			)
		)
		(property "MPN" "TPD1E0B04DPYR"
			(at 56.65 238.25 0)
			(layer "F.Fab")
			(hide yes)
			(effects
				(font
					(size 1 1)
					(thickness 0.15)
				)
			)
		)
		(property "Manufacturer" "Texas Instruments"
			(at 56.65 238.25 0)
			(layer "F.Fab")
			(hide yes)
			(effects
				(font
					(size 1 1)
					(thickness 0.15)
				)
			)
		)
		(property "Author" "Antmicro"
			(at 56.65 238.25 0)
			(layer "F.Fab")
			(hide yes)
			(effects
				(font
					(size 1 1)
					(thickness 0.15)
				)
			)
		)
		(property "License" "Apache-2.0"
			(at 56.65 238.25 0)
			(layer "F.Fab")
			(hide yes)
			(effects
				(font
					(size 1 1)
					(thickness 0.15)
				)
			)
		)
		(sheetname "Peripherals")
		(sheetfile "peripherals.kicad_sch")
		(attr smd)
		(fp_rect
			(start -0.725 -0.475)
			(end 0.725 0.475)
			(stroke
				(width 0.05)
				(type solid)
			)
			(fill none)
			(layer "F.CrtYd")
		)
		(fp_rect
			(start -0.55 -0.35)
			(end 0.55 0.35)
			(stroke
				(width 0.15)
				(type solid)
			)
			(fill none)
			(layer "F.Fab")
		)
		(fp_text user "Author: Antmicro"
			(at -0.8 4.4 -90)
			(layer "F.Fab")
			(hide yes)
			(effects
				(font
					(size 0.7 0.7)
					(thickness 0.15)
				)
				(justify left bottom)
			)
		)
		(fp_text user "${REFERENCE}"
			(at -0.8 3.2 -90)
			(layer "F.Fab")
			(hide yes)
			(effects
				(font
					(size 0.7 0.7)
					(thickness 0.15)
				)
				(justify left bottom)
			)
		)
		(fp_text user "License: Apache-2.0"
			(at -0.8 5.6 -90)
			(layer "F.Fab")
			(hide yes)
			(effects
				(font
					(size 0.7 0.7)
					(thickness 0.15)
				)
				(justify left bottom)
			)
		)
		(pad "1" smd roundrect
			(at -0.351 0 270)
			(size 0.3 0.5)
			(layers "F.Cu" "F.Paste" "F.Mask")
			(roundrect_rratio 0.25)
			(net 472 "PCIE3_CLK_P")
			(pinfunction "C")
			(pintype "passive")
		)
		(pad "2" smd roundrect
			(at 0.349 0 270)
			(size 0.3 0.5)
			(layers "F.Cu" "F.Paste" "F.Mask")
			(roundrect_rratio 0.25)
			(net 1 "GND")
			(pinfunction "A")
			(pintype "passive")
		)
	)
	(footprint "antmicro-footprints:XDFN-2_1x0.60mm"
		(layer "F.Cu")
		(at 131.4 123.34 90)
		(property "Reference" "D57"
			(at 0.69 -1.45 -90)
			(layer "F.SilkS")
			(effects
				(font
					(size 0.7 0.7)
					(thickness 0.15)
				)
				(justify left bottom)
			)
		)
		(property "Value" "TPD1E0B04_XDFN-2"
			(at 0 1.5 90)
			(layer "F.Fab")
			(effects
				(font
					(size 0.7 0.7)
					(thickness 0.15)
				)
				(justify left bottom)
			)
		)
		(property "Footprint" "antmicro-footprints:XDFN-2_1x0.60mm"
			(at 0 0 90)
			(layer "F.Fab")
			(hide yes)
			(effects
				(font
					(size 1.27 1.27)
					(thickness 0.15)
				)
			)
		)
		(property "Datasheet" "https://www.ti.com/general/docs/suppproductinfo.tsp?distId=26&gotoUrl=https://www.ti.com/lit/gpn/tpd1e0b04"
			(at 0 0 90)
			(layer "F.Fab")
			(hide yes)
			(effects
				(font
					(size 1.27 1.27)
					(thickness 0.15)
				)
			)
		)
		(property "MPN" "TPD1E0B04DPYR"
			(at 254.74 -8.06 0)
			(layer "F.Fab")
			(hide yes)
			(effects
				(font
					(size 1 1)
					(thickness 0.15)
				)
			)
		)
		(property "Manufacturer" "Texas Instruments"
			(at 254.74 -8.06 0)
			(layer "F.Fab")
			(hide yes)
			(effects
				(font
					(size 1 1)
					(thickness 0.15)
				)
			)
		)
		(property "Author" "Antmicro"
			(at 254.74 -8.06 0)
			(layer "F.Fab")
			(hide yes)
			(effects
				(font
					(size 1 1)
					(thickness 0.15)
				)
			)
		)
		(property "License" "Apache-2.0"
			(at 254.74 -8.06 0)
			(layer "F.Fab")
			(hide yes)
			(effects
				(font
					(size 1 1)
					(thickness 0.15)
				)
			)
		)
		(sheetname "Peripherals")
		(sheetfile "peripherals.kicad_sch")
		(attr smd)
		(fp_rect
			(start -0.725 -0.475)
			(end 0.725 0.475)
			(stroke
				(width 0.05)
				(type solid)
			)
			(fill none)
			(layer "F.CrtYd")
		)
		(fp_rect
			(start -0.55 -0.35)
			(end 0.55 0.35)
			(stroke
				(width 0.15)
				(type solid)
			)
			(fill none)
			(layer "F.Fab")
		)
		(fp_text user "${REFERENCE}"
			(at -0.8 3.2 90)
			(layer "F.Fab")
			(hide yes)
			(effects
				(font
					(size 0.7 0.7)
					(thickness 0.15)
				)
				(justify left bottom)
			)
		)
		(fp_text user "Author: Antmicro"
			(at -0.8 4.4 90)
			(layer "F.Fab")
			(hide yes)
			(effects
				(font
					(size 0.7 0.7)
					(thickness 0.15)
				)
				(justify left bottom)
			)
		)
		(fp_text user "License: Apache-2.0"
			(at -0.8 5.6 90)
			(layer "F.Fab")
			(hide yes)
			(effects
				(font
					(size 0.7 0.7)
					(thickness 0.15)
				)
				(justify left bottom)
			)
		)
		(pad "1" smd roundrect
			(at -0.351 0 90)
			(size 0.3 0.5)
			(layers "F.Cu" "F.Paste" "F.Mask")
			(roundrect_rratio 0.25)
			(net 1 "GND")
			(pinfunction "C")
			(pintype "passive")
		)
		(pad "2" smd roundrect
			(at 0.349 0 90)
			(size 0.3 0.5)
			(layers "F.Cu" "F.Paste" "F.Mask")
			(roundrect_rratio 0.25)
			(net 660 "I2C1_SDA")
			(pinfunction "A")
			(pintype "passive")
		)
	)
	(footprint "antmicro-footprints:C_0402_1005Metric"
		(layer "F.Cu")
		(at 136.35 86.25 180)
		(descr "Capacitor SMD 0402")
		(tags "capacitor SMD 0402")
		(property "Reference" "C108"
			(at 3.65 -0.45 180)
			(layer "F.SilkS")
			(effects
				(font
					(size 0.7 0.7)
					(thickness 0.15)
				)
				(justify left bottom)
			)
		)
		(property "Value" "C_220n_0402"
			(at 0 1.4 180)
			(layer "F.Fab")
			(effects
				(font
					(size 0.7 0.7)
					(thickness 0.15)
				)
				(justify left bottom)
			)
		)
		(property "Footprint" "antmicro-footprints:C_0402_1005Metric"
			(at 0 0 180)
			(layer "F.Fab")
			(hide yes)
			(effects
				(font
					(size 1.27 1.27)
					(thickness 0.15)
				)
			)
		)
		(property "Datasheet" "https://www.yageo.com/en/Chart/Download/pdf/CC0402KRX5R6BB224"
			(at 0 0 180)
			(layer "F.Fab")
			(hide yes)
			(effects
				(font
					(size 1.27 1.27)
					(thickness 0.15)
				)
			)
		)
		(property "Author" "Antmicro"
			(at 272.7 172.5 0)
			(layer "F.Fab")
			(hide yes)
			(effects
				(font
					(size 1 1)
					(thickness 0.15)
				)
			)
		)
		(property "Dielectric" ""
			(at 272.7 172.5 0)
			(layer "F.Fab")
			(hide yes)
			(effects
				(font
					(size 1 1)
					(thickness 0.15)
				)
			)
		)
		(property "License" "Apache-2.0"
			(at 272.7 172.5 0)
			(layer "F.Fab")
			(hide yes)
			(effects
				(font
					(size 1 1)
					(thickness 0.15)
				)
			)
		)
		(property "MPN" "CC0402KRX5R6BB224"
			(at 272.7 172.5 0)
			(layer "F.Fab")
			(hide yes)
			(effects
				(font
					(size 1 1)
					(thickness 0.15)
				)
			)
		)
		(property "Manufacturer" "YAGEO"
			(at 272.7 172.5 0)
			(layer "F.Fab")
			(hide yes)
			(effects
				(font
					(size 1 1)
					(thickness 0.15)
				)
			)
		)
		(property "Val" "220n"
			(at 272.7 172.5 0)
			(layer "F.Fab")
			(hide yes)
			(effects
				(font
					(size 1 1)
					(thickness 0.15)
				)
			)
		)
		(property "Voltage" ""
			(at 272.7 172.5 0)
			(layer "F.Fab")
			(hide yes)
			(effects
				(font
					(size 1 1)
					(thickness 0.15)
				)
			)
		)
		(sheetname "Peripherals")
		(sheetfile "peripherals.kicad_sch")
		(attr smd)
		(fp_rect
			(start -0.925 -0.47)
			(end 0.925 0.47)
			(stroke
				(width 0.05)
				(type default)
			)
			(fill none)
			(layer "F.CrtYd")
		)
		(fp_line
			(start 0.504 0.248)
			(end -0.494 0.248)
			(stroke
				(width 0.15)
				(type solid)
			)
			(layer "F.Fab")
		)
		(fp_line
			(start 0.504 -0.25)
			(end 0.504 0.248)
			(stroke
				(width 0.15)
				(type solid)
			)
			(layer "F.Fab")
		)
		(fp_line
			(start -0.494 0.248)
			(end -0.494 -0.25)
			(stroke
				(width 0.15)
				(type solid)
			)
			(layer "F.Fab")
		)
		(fp_line
			(start -0.494 -0.25)
			(end 0.504 -0.25)
			(stroke
				(width 0.15)
				(type solid)
			)
			(layer "F.Fab")
		)
		(fp_text user "License: Apache-2.0"
			(at -0.932 5.17 180)
			(layer "F.Fab")
			(hide yes)
			(effects
				(font
					(size 0.7 0.7)
					(thickness 0.15)
				)
				(justify left bottom)
			)
		)
		(fp_text user "Author: Antmicro"
			(at -0.932 4.17 180)
			(layer "F.Fab")
			(hide yes)
			(effects
				(font
					(size 0.7 0.7)
					(thickness 0.15)
				)
				(justify left bottom)
			)
		)
		(fp_text user "${REFERENCE}"
			(at -0.932 3.168 180)
			(layer "F.Fab")
			(hide yes)
			(effects
				(font
					(size 0.7 0.7)
					(thickness 0.15)
				)
				(justify left bottom)
			)
		)
		(pad "1" smd roundrect
			(at -0.48 0 180)
			(size 0.59 0.64)
			(layers "F.Cu" "F.Paste" "F.Mask")
			(roundrect_rratio 0.25)
			(net 411 "/Peripherals/PCIE2_TX0_CONN_N")
			(pintype "passive")
		)
		(pad "2" smd roundrect
			(at 0.48 0 180)
			(size 0.59 0.64)
			(layers "F.Cu" "F.Paste" "F.Mask")
			(roundrect_rratio 0.25)
			(net 156 "PCIE2_TX0_N")
			(pintype "passive")
		)
	)
	(footprint "antmicro-footprints:C_0402_1005Metric"
		(layer "F.Cu")
		(at 74.6 110.967469 -90)
		(descr "Capacitor SMD 0402")
		(tags "capacitor SMD 0402")
		(property "Reference" "C62"
			(at 2.982531 -0.4 -90)
			(layer "F.SilkS")
			(effects
				(font
					(size 0.7 0.7)
					(thickness 0.15)
				)
				(justify left bottom)
			)
		)
		(property "Value" "C_100n_0402"
			(at 0 1.4 -90)
			(layer "F.Fab")
			(effects
				(font
					(size 0.7 0.7)
					(thickness 0.15)
				)
				(justify left bottom)
			)
		)
		(property "Footprint" "antmicro-footprints:C_0402_1005Metric"
			(at 0 0 -90)
			(layer "F.Fab")
			(hide yes)
			(effects
				(font
					(size 1.27 1.27)
					(thickness 0.15)
				)
			)
		)
		(property "Datasheet" "https://www.murata.com/products/productdetail?partno=GRM155R61H104KE14%23"
			(at 0 0 -90)
			(layer "F.Fab")
			(hide yes)
			(effects
				(font
					(size 1.27 1.27)
					(thickness 0.15)
				)
			)
		)
		(property "Author" "Antmicro"
			(at -36.367469 185.567469 0)
			(layer "F.Fab")
			(hide yes)
			(effects
				(font
					(size 1 1)
					(thickness 0.15)
				)
			)
		)
		(property "Dielectric" "X5R"
			(at -36.367469 185.567469 0)
			(layer "F.Fab")
			(hide yes)
			(effects
				(font
					(size 1 1)
					(thickness 0.15)
				)
			)
		)
		(property "License" "Apache-2.0"
			(at -36.367469 185.567469 0)
			(layer "F.Fab")
			(hide yes)
			(effects
				(font
					(size 1 1)
					(thickness 0.15)
				)
			)
		)
		(property "MPN" "GRM155R61H104KE14D"
			(at -36.367469 185.567469 0)
			(layer "F.Fab")
			(hide yes)
			(effects
				(font
					(size 1 1)
					(thickness 0.15)
				)
			)
		)
		(property "Manufacturer" "Murata"
			(at -36.367469 185.567469 0)
			(layer "F.Fab")
			(hide yes)
			(effects
				(font
					(size 1 1)
					(thickness 0.15)
				)
			)
		)
		(property "Val" "100n"
			(at -36.367469 185.567469 0)
			(layer "F.Fab")
			(hide yes)
			(effects
				(font
					(size 1 1)
					(thickness 0.15)
				)
			)
		)
		(property "Voltage" "50V"
			(at -36.367469 185.567469 0)
			(layer "F.Fab")
			(hide yes)
			(effects
				(font
					(size 1 1)
					(thickness 0.15)
				)
			)
		)
		(sheetname "USB Debug, DP")
		(sheetfile "usb.kicad_sch")
		(attr smd)
		(fp_rect
			(start -0.925 -0.47)
			(end 0.925 0.47)
			(stroke
				(width 0.05)
				(type default)
			)
			(fill none)
			(layer "F.CrtYd")
		)
		(fp_line
			(start -0.494 0.248)
			(end -0.494 -0.25)
			(stroke
				(width 0.15)
				(type solid)
			)
			(layer "F.Fab")
		)
		(fp_line
			(start 0.504 0.248)
			(end -0.494 0.248)
			(stroke
				(width 0.15)
				(type solid)
			)
			(layer "F.Fab")
		)
		(fp_line
			(start -0.494 -0.25)
			(end 0.504 -0.25)
			(stroke
				(width 0.15)
				(type solid)
			)
			(layer "F.Fab")
		)
		(fp_line
			(start 0.504 -0.25)
			(end 0.504 0.248)
			(stroke
				(width 0.15)
				(type solid)
			)
			(layer "F.Fab")
		)
		(fp_text user "${REFERENCE}"
			(at -0.932 3.168 -90)
			(layer "F.Fab")
			(hide yes)
			(effects
				(font
					(size 0.7 0.7)
					(thickness 0.15)
				)
				(justify left bottom)
			)
		)
		(fp_text user "License: Apache-2.0"
			(at -0.932 5.17 -90)
			(layer "F.Fab")
			(hide yes)
			(effects
				(font
					(size 0.7 0.7)
					(thickness 0.15)
				)
				(justify left bottom)
			)
		)
		(fp_text user "Author: Antmicro"
			(at -0.932 4.17 -90)
			(layer "F.Fab")
			(hide yes)
			(effects
				(font
					(size 0.7 0.7)
					(thickness 0.15)
				)
				(justify left bottom)
			)
		)
		(pad "1" smd roundrect
			(at -0.48 0 270)
			(size 0.59 0.64)
			(layers "F.Cu" "F.Paste" "F.Mask")
			(roundrect_rratio 0.25)
			(net 197 "/USB Debug, DP/USBC0_TX1_N")
			(pintype "passive")
		)
		(pad "2" smd roundrect
			(at 0.48 0 270)
			(size 0.59 0.64)
			(layers "F.Cu" "F.Paste" "F.Mask")
			(roundrect_rratio 0.25)
			(net 198 "/USB Debug, DP/USBC0_CONN_TX1_N")
			(pintype "passive")
		)
	)
)
